(kicad_pcb
	(version 20260206)
	(generator "pcbnew")
	(generator_version "10.0")
	(general
		(thickness 1.6)
		(legacy_teardrops no)
	)
	(paper "A4")
	(title_block
		(title "v1-tray-backplane — T6M_tray_BP_c_1023_1120.brd")
		(comment 1 "Open CloudServer (Microsoft) / footprints 73-74 of 170")
	)
	(layers
		(0 "F.Cu" signal "TOP")
		(4 "In1.Cu" signal "GND")
		(6 "In2.Cu" signal "IN1")
		(8 "In3.Cu" signal "VCC")
		(10 "In4.Cu" signal "VCC1")
		(12 "In5.Cu" signal "IN2")
		(14 "In6.Cu" signal "GND1")
		(2 "B.Cu" signal "BOTTOM")
		(9 "F.Adhes" user "F.Adhesive")
		(11 "B.Adhes" user "B.Adhesive")
		(13 "F.Paste" user "Package Geometry/Pastemask Top")
		(15 "B.Paste" user "Package Geometry/Pastemask Bottom")
		(5 "F.SilkS" user "Ref Des/Silkscreen Top")
		(7 "B.SilkS" user "Ref Des/Silkscreen Bottom")
		(1 "F.Mask" user "Board Geometry/Soldermask Top")
		(3 "B.Mask" user "Board Geometry/Soldermask Bottom")
		(17 "Dwgs.User" user "User.Drawings")
		(19 "Cmts.User" user "User.Comments")
		(21 "Eco1.User" user "User.Eco1")
		(23 "Eco2.User" user "User.Eco2")
		(25 "Edge.Cuts" user "Board Geometry/Outline")
		(27 "Margin" user)
		(31 "F.CrtYd" user "Package Geometry/Place Bound Top")
		(29 "B.CrtYd" user "Package Geometry/Place Bound Bottom")
		(35 "F.Fab" user "Ref Des/Assembly Top")
		(33 "B.Fab" user "Ref Des/Assembly Bottom")
	)
	(footprint ""
		(layer "F.Cu")
		(at 313.07024 -26.126694)
		(property "Reference" "R32"
			(at -6.604 -1.565148 0)
			(unlocked yes)
			(layer "F.SilkS")
			(effects
				(font
					(size 0.7874 0.5842)
					(thickness 0.1524)
				)
				(justify left)
			)
		)
		(property "Value" ""
			(at 0 0 0)
			(layer "F.Fab")
			(effects
				(font
					(size 1.27 1.27)
				)
			)
		)
		(duplicate_pad_numbers_are_jumpers no)
		(fp_line
			(start -0.7874 -0.4064)
			(end 0.7874 -0.4064)
			(stroke
				(width 0.1524)
				(type default)
			)
			(layer "F.SilkS")
		)
		(fp_line
			(start -0.7874 0.4064)
			(end -0.7874 -0.4064)
			(stroke
				(width 0.1524)
				(type default)
			)
			(layer "F.SilkS")
		)
		(fp_line
			(start 0.7874 -0.4064)
			(end 0.7874 0.4064)
			(stroke
				(width 0.1524)
				(type default)
			)
			(layer "F.SilkS")
		)
		(fp_line
			(start 0.7874 0.4064)
			(end -0.7874 0.4064)
			(stroke
				(width 0.1524)
				(type default)
			)
			(layer "F.SilkS")
		)
		(fp_poly
			(pts
				(xy -0.508 0.2794) (xy -0.508 0.2286) (xy -0.635 0.2286) (xy -0.635 -0.254) (xy -0.5334 -0.254)
				(xy -0.5334 -0.2794) (xy 0.5334 -0.2794) (xy 0.5334 -0.254) (xy 0.635 -0.254) (xy 0.635 0.254) (xy 0.5334 0.254)
				(xy 0.5334 0.2794)
			)
			(stroke
				(width 0)
				(type default)
			)
			(fill no)
			(layer "F.CrtYd")
		)
		(pad "1" smd rect
			(at 0.40005 0)
			(size 0.4572 0.508)
			(layers "F.Cu" "F.Mask" "F.Paste")
			(net "P3V3_BLAD2")
		)
		(pad "2" smd rect
			(at -0.40005 0)
			(size 0.4572 0.508)
			(layers "F.Cu" "F.Mask" "F.Paste")
			(net "ENET10G_4_RS1")
		)
	)
	(footprint ""
		(layer "F.Cu")
		(at 92.331286 -35.377628 180)
		(property "Reference" "FS4"
			(at 2.872232 4.248404 0)
			(unlocked yes)
			(layer "F.SilkS")
			(effects
				(font
					(size 0.7874 0.5842)
					(thickness 0.1524)
				)
				(justify left)
			)
		)
		(property "Value" ""
			(at 0 0 180)
			(layer "F.Fab")
			(effects
				(font
					(size 1.27 1.27)
				)
			)
		)
		(duplicate_pad_numbers_are_jumpers no)
		(fp_line
			(start 3.550412 1.050036)
			(end -0.650494 1.050036)
			(stroke
				(width 0.1524)
				(type default)
			)
			(layer "F.SilkS")
		)
		(fp_line
			(start 3.550412 -1.050036)
			(end 3.550412 1.050036)
			(stroke
				(width 0.1524)
				(type default)
			)
			(layer "F.SilkS")
		)
		(fp_line
			(start -0.650494 1.050036)
			(end -0.650494 -1.050036)
			(stroke
				(width 0.1524)
				(type default)
			)
			(layer "F.SilkS")
		)
		(fp_line
			(start -0.650494 -1.050036)
			(end 3.550412 -1.050036)
			(stroke
				(width 0.1524)
				(type default)
			)
			(layer "F.SilkS")
		)
		(fp_poly
			(pts
				(xy 3.228086 -0.9652) (xy 3.228086 -1.100074) (xy -0.327914 -1.100074) (xy -0.327914 -0.9652) (xy -0.556514 -0.9652)
				(xy -0.556514 0.9652) (xy -0.327914 0.9652) (xy -0.327914 1.100074) (xy 3.228086 1.100074) (xy 3.228086 0.9652)
				(xy 3.456686 0.9652) (xy 3.456686 -0.9652)
			)
			(stroke
				(width 0)
				(type default)
			)
			(fill no)
			(layer "F.CrtYd")
		)
		(fp_text user "2"
			(at 4.434586 0.286004 0)
			(unlocked yes)
			(layer "F.SilkS")
			(effects
				(font
					(size 0.7874 0.5842)
					(thickness 0.1524)
				)
				(justify left)
			)
		)
		(fp_text user "1"
			(at -0.645414 -1.415796 0)
			(unlocked yes)
			(layer "F.SilkS")
			(effects
				(font
					(size 0.7874 0.5842)
					(thickness 0.1524)
				)
				(justify left)
			)
		)
		(pad "1" smd rect
			(at 0 0 180)
			(size 1.016 1.8034)
			(layers "F.Cu" "F.Mask" "F.Paste")
			(net "P3V3_BLAD1")
		)
		(pad "2" smd rect
			(at 2.899918 0 180)
			(size 1.016 1.8034)
			(layers "F.Cu" "F.Mask" "F.Paste")
			(net "P3V3_10G_2_VCCR_L")
		)
	)
)
